(kicad_pcb
	(version 20260206)
	(generator "pcbnew")
	(generator_version "10.0")
	(general
		(thickness 1.6)
		(legacy_teardrops no)
	)
	(paper "A4")
	(title_block
		(title "Bryce Canyon_F.DPB_16315-1-OCP.brd")
		(comment 1 "Bryce Canyon / footprints 240-246 of 2223")
	)
	(layers
		(0 "F.Cu" signal "TOP")
		(4 "In1.Cu" signal "L2GND")
		(6 "In2.Cu" signal "L3")
		(8 "In3.Cu" signal "L4GND")
		(10 "In4.Cu" signal "L5")
		(12 "In5.Cu" signal "L6VCC")
		(14 "In6.Cu" signal "L7VCC")
		(16 "In7.Cu" signal "L8")
		(18 "In8.Cu" signal "L9GND")
		(20 "In9.Cu" signal "L10")
		(22 "In10.Cu" signal "L11GND")
		(2 "B.Cu" signal "BOTTOM")
		(9 "F.Adhes" user "F.Adhesive")
		(11 "B.Adhes" user "B.Adhesive")
		(13 "F.Paste" user "Package Geometry/Pastemask Top")
		(15 "B.Paste" user "Package Geometry/Pastemask Bottom")
		(5 "F.SilkS" user "Ref Des/Silkscreen Top")
		(7 "B.SilkS" user "Ref Des/Silkscreen Bottom")
		(1 "F.Mask" user "Board Geometry/Soldermask Top")
		(3 "B.Mask" user "Board Geometry/Soldermask Bottom")
		(17 "Dwgs.User" user "User.Drawings")
		(19 "Cmts.User" user "User.Comments")
		(21 "Eco1.User" user "User.Eco1")
		(23 "Eco2.User" user "User.Eco2")
		(25 "Edge.Cuts" user "Board Geometry/Outline")
		(27 "Margin" user)
		(31 "F.CrtYd" user "Package Geometry/Place Bound Top")
		(29 "B.CrtYd" user "Package Geometry/Place Bound Bottom")
		(35 "F.Fab" user "Ref Des/Assembly Top")
		(33 "B.Fab" user "Ref Des/Assembly Bottom")
	)
	(footprint ""
		(layer "F.Cu")
		(at 346.192602 -291.356542 90)
		(property "Reference" "R588"
			(at 0 0 90)
			(layer "F.SilkS")
			(hide yes)
			(effects
				(font
					(size 1.27 1.27)
				)
			)
		)
		(property "Value" "4K7R2J-2-GP"
			(at 0.064008 -3.993896 90)
			(unlocked yes)
			(layer "F.Fab")
			(hide yes)
			(effects
				(font
					(size 1.016 1.016)
					(thickness 0.1524)
				)
			)
		)
		(property "Device Type" "R402H16"
			(at 0.064008 -5.517896 90)
			(unlocked yes)
			(layer "F.Fab")
			(hide yes)
			(effects
				(font
					(size 1.016 1.016)
					(thickness 0.1524)
				)
			)
		)
		(duplicate_pad_numbers_are_jumpers no)
		(fp_line
			(start 0.508 -0.9398)
			(end -0.508 -0.9398)
			(stroke
				(width 0.1524)
				(type default)
			)
			(layer "F.SilkS")
		)
		(fp_line
			(start -0.508 -0.9398)
			(end -0.508 0.9398)
			(stroke
				(width 0.1524)
				(type default)
			)
			(layer "F.SilkS")
		)
		(fp_rect
			(start -0.508 0.9398)
			(end 0.508 -0.9398)
			(stroke
				(width 0)
				(type default)
			)
			(fill no)
			(layer "F.CrtYd")
		)
		(fp_rect
			(start -0.508 0.9398)
			(end 0.508 -0.9398)
			(stroke
				(width 0)
				(type default)
			)
			(fill no)
			(layer "F.Fab")
		)
		(pad "1" smd custom
			(at 0 -0.4445 90)
			(size 0.1397 0.1397)
			(layers "F.Cu" "F.Mask" "F.Paste")
			(net "DRIVE_B_31_FLT_LED")
			(options
				(clearance outline)
				(anchor circle)
			)
			(primitives
				(gr_poly
					(pts
						(arc
							(start -0.1778 -0.2794)
							(mid -0.249642 -0.249642)
							(end -0.2794 -0.1778)
						)
						(arc
							(start -0.2794 0.1778)
							(mid -0.249642 0.249642)
							(end -0.1778 0.2794)
						)
						(arc
							(start 0.1778 0.2794)
							(mid 0.249642 0.249642)
							(end 0.2794 0.1778)
						)
						(arc
							(start 0.2794 -0.1778)
							(mid 0.249642 -0.249642)
							(end 0.1778 -0.2794)
						)
					)
					(width 0)
					(fill yes)
				)
			)
		)
		(pad "2" smd custom
			(at 0 0.4445 90)
			(size 0.1397 0.1397)
			(layers "F.Cu" "F.Mask" "F.Paste")
			(net "GND")
			(options
				(clearance outline)
				(anchor circle)
			)
			(primitives
				(gr_poly
					(pts
						(arc
							(start -0.1778 -0.2794)
							(mid -0.249642 -0.249642)
							(end -0.2794 -0.1778)
						)
						(arc
							(start -0.2794 0.1778)
							(mid -0.249642 0.249642)
							(end -0.1778 0.2794)
						)
						(arc
							(start 0.1778 0.2794)
							(mid 0.249642 0.249642)
							(end 0.2794 0.1778)
						)
						(arc
							(start 0.2794 -0.1778)
							(mid 0.249642 -0.249642)
							(end 0.1778 -0.2794)
						)
					)
					(width 0)
					(fill yes)
				)
			)
		)
	)
	(footprint ""
		(layer "F.Cu")
		(at 370.259102 -57.851294 90)
		(property "Reference" "C452"
			(at 0 0 90)
			(layer "F.SilkS")
			(hide yes)
			(effects
				(font
					(size 1.27 1.27)
				)
			)
		)
		(property "Value" "SCD033U25V2KX-GP"
			(at 1.1811 -2.7051 90)
			(unlocked yes)
			(layer "F.Fab")
			(hide yes)
			(effects
				(font
					(size 1.016 1.016)
					(thickness 0.1524)
				)
			)
		)
		(property "Device Type" "C402H22"
			(at 1.1811 -4.2291 90)
			(unlocked yes)
			(layer "F.Fab")
			(hide yes)
			(effects
				(font
					(size 1.016 1.016)
					(thickness 0.1524)
				)
			)
		)
		(duplicate_pad_numbers_are_jumpers no)
		(fp_rect
			(start -0.4318 0.9525)
			(end 0.4318 -0.9525)
			(stroke
				(width 0)
				(type default)
			)
			(fill no)
			(layer "F.CrtYd")
		)
		(fp_rect
			(start -0.4318 0.9525)
			(end 0.4318 -0.9525)
			(stroke
				(width 0)
				(type default)
			)
			(fill no)
			(layer "F.Fab")
		)
		(pad "1" smd custom
			(at 0 -0.4445 90)
			(size 0.1524 0.1524)
			(layers "F.Cu" "F.Mask" "F.Paste")
			(net "P12V_A")
			(options
				(clearance outline)
				(anchor circle)
			)
			(primitives
				(gr_poly
					(pts
						(arc
							(start 0.3048 -0.2032)
							(mid 0.275042 -0.275042)
							(end 0.2032 -0.3048)
						)
						(arc
							(start -0.2032 -0.3048)
							(mid -0.275042 -0.275042)
							(end -0.3048 -0.2032)
						)
						(arc
							(start -0.3048 0.2032)
							(mid -0.275042 0.275042)
							(end -0.2032 0.3048)
						)
						(arc
							(start 0.2032 0.3048)
							(mid 0.275042 0.275042)
							(end 0.3048 0.2032)
						)
					)
					(width 0)
					(fill yes)
				)
			)
		)
		(pad "2" smd custom
			(at 0 0.4445 90)
			(size 0.1524 0.1524)
			(layers "F.Cu" "F.Mask" "F.Paste")
			(net "SW_HDD_N31")
			(options
				(clearance outline)
				(anchor circle)
			)
			(primitives
				(gr_poly
					(pts
						(arc
							(start 0.3048 -0.2032)
							(mid 0.275042 -0.275042)
							(end 0.2032 -0.3048)
						)
						(arc
							(start -0.2032 -0.3048)
							(mid -0.275042 -0.275042)
							(end -0.3048 -0.2032)
						)
						(arc
							(start -0.3048 0.2032)
							(mid -0.275042 0.275042)
							(end -0.2032 0.3048)
						)
						(arc
							(start 0.2032 0.3048)
							(mid 0.275042 0.275042)
							(end 0.3048 0.2032)
						)
					)
					(width 0)
					(fill yes)
				)
			)
		)
	)
	(footprint ""
		(layer "F.Cu")
		(at 260.8326 -229.6668 -90)
		(property "Reference" "R432"
			(at 0 0 270)
			(layer "F.SilkS")
			(hide yes)
			(effects
				(font
					(size 1.27 1.27)
				)
			)
		)
		(property "Value" "1KR2F-3-GP"
			(at 0.064008 -3.993896 270)
			(unlocked yes)
			(layer "F.Fab")
			(hide yes)
			(effects
				(font
					(size 1.016 1.016)
					(thickness 0.1524)
				)
			)
		)
		(property "Device Type" "R402H16"
			(at 0.064008 -5.517896 270)
			(unlocked yes)
			(layer "F.Fab")
			(hide yes)
			(effects
				(font
					(size 1.016 1.016)
					(thickness 0.1524)
				)
			)
		)
		(duplicate_pad_numbers_are_jumpers no)
		(fp_line
			(start -0.508 -0.9398)
			(end -0.508 0.9398)
			(stroke
				(width 0.1524)
				(type default)
			)
			(layer "F.SilkS")
		)
		(fp_line
			(start 0.508 -0.9398)
			(end -0.508 -0.9398)
			(stroke
				(width 0.1524)
				(type default)
			)
			(layer "F.SilkS")
		)
		(fp_rect
			(start -0.508 0.9398)
			(end 0.508 -0.9398)
			(stroke
				(width 0)
				(type default)
			)
			(fill no)
			(layer "F.CrtYd")
		)
		(fp_rect
			(start -0.508 0.9398)
			(end 0.508 -0.9398)
			(stroke
				(width 0)
				(type default)
			)
			(fill no)
			(layer "F.Fab")
		)
		(pad "1" smd custom
			(at 0 -0.4445 270)
			(size 0.1397 0.1397)
			(layers "F.Cu" "F.Mask" "F.Paste")
			(net "P3V3_STBY_A")
			(options
				(clearance outline)
				(anchor circle)
			)
			(primitives
				(gr_poly
					(pts
						(arc
							(start -0.1778 -0.2794)
							(mid -0.249642 -0.249642)
							(end -0.2794 -0.1778)
						)
						(arc
							(start -0.2794 0.1778)
							(mid -0.249642 0.249642)
							(end -0.1778 0.2794)
						)
						(arc
							(start 0.1778 0.2794)
							(mid 0.249642 0.249642)
							(end 0.2794 0.1778)
						)
						(arc
							(start 0.2794 -0.1778)
							(mid 0.249642 -0.249642)
							(end 0.1778 -0.2794)
						)
					)
					(width 0)
					(fill yes)
				)
			)
		)
		(pad "2" smd custom
			(at 0 0.4445 270)
			(size 0.1397 0.1397)
			(layers "F.Cu" "F.Mask" "F.Paste")
			(net "I2C_DRIVE_A_PWR_SDA")
			(options
				(clearance outline)
				(anchor circle)
			)
			(primitives
				(gr_poly
					(pts
						(arc
							(start -0.1778 -0.2794)
							(mid -0.249642 -0.249642)
							(end -0.2794 -0.1778)
						)
						(arc
							(start -0.2794 0.1778)
							(mid -0.249642 0.249642)
							(end -0.1778 0.2794)
						)
						(arc
							(start 0.1778 0.2794)
							(mid 0.249642 0.249642)
							(end 0.2794 0.1778)
						)
						(arc
							(start 0.2794 -0.1778)
							(mid 0.249642 -0.249642)
							(end 0.1778 -0.2794)
						)
					)
					(width 0)
					(fill yes)
				)
			)
		)
	)
	(footprint ""
		(layer "F.Cu")
		(at 190.8048 -52.197 -90)
		(property "Reference" "R797"
			(at 0 0 270)
			(layer "F.SilkS")
			(hide yes)
			(effects
				(font
					(size 1.27 1.27)
				)
			)
		)
		(property "Value" "10KR2F-2-GP"
			(at 0.064008 -3.993896 270)
			(unlocked yes)
			(layer "F.Fab")
			(hide yes)
			(effects
				(font
					(size 1.016 1.016)
					(thickness 0.1524)
				)
			)
		)
		(property "Device Type" "R402H16"
			(at 0.064008 -5.517896 270)
			(unlocked yes)
			(layer "F.Fab")
			(hide yes)
			(effects
				(font
					(size 1.016 1.016)
					(thickness 0.1524)
				)
			)
		)
		(duplicate_pad_numbers_are_jumpers no)
		(fp_line
			(start -0.508 -0.9398)
			(end -0.508 0.9398)
			(stroke
				(width 0.1524)
				(type default)
			)
			(layer "F.SilkS")
		)
		(fp_line
			(start 0.508 -0.9398)
			(end -0.508 -0.9398)
			(stroke
				(width 0.1524)
				(type default)
			)
			(layer "F.SilkS")
		)
		(fp_rect
			(start -0.508 0.9398)
			(end 0.508 -0.9398)
			(stroke
				(width 0)
				(type default)
			)
			(fill no)
			(layer "F.CrtYd")
		)
		(fp_rect
			(start -0.508 0.9398)
			(end 0.508 -0.9398)
			(stroke
				(width 0)
				(type default)
			)
			(fill no)
			(layer "F.Fab")
		)
		(pad "1" smd custom
			(at 0 -0.4445 270)
			(size 0.1397 0.1397)
			(layers "F.Cu" "F.Mask" "F.Paste")
			(net "P3V3_STBY_A")
			(options
				(clearance outline)
				(anchor circle)
			)
			(primitives
				(gr_poly
					(pts
						(arc
							(start -0.1778 -0.2794)
							(mid -0.249642 -0.249642)
							(end -0.2794 -0.1778)
						)
						(arc
							(start -0.2794 0.1778)
							(mid -0.249642 0.249642)
							(end -0.1778 0.2794)
						)
						(arc
							(start 0.1778 0.2794)
							(mid 0.249642 0.249642)
							(end 0.2794 0.1778)
						)
						(arc
							(start 0.2794 -0.1778)
							(mid 0.249642 -0.249642)
							(end 0.1778 -0.2794)
						)
					)
					(width 0)
					(fill yes)
				)
			)
		)
		(pad "2" smd custom
			(at 0 0.4445 270)
			(size 0.1397 0.1397)
			(layers "F.Cu" "F.Mask" "F.Paste")
			(net "HDD_PRSNT_29")
			(options
				(clearance outline)
				(anchor circle)
			)
			(primitives
				(gr_poly
					(pts
						(arc
							(start -0.1778 -0.2794)
							(mid -0.249642 -0.249642)
							(end -0.2794 -0.1778)
						)
						(arc
							(start -0.2794 0.1778)
							(mid -0.249642 0.249642)
							(end -0.1778 0.2794)
						)
						(arc
							(start 0.1778 0.2794)
							(mid 0.249642 0.249642)
							(end 0.2794 0.1778)
						)
						(arc
							(start 0.2794 -0.1778)
							(mid 0.249642 -0.249642)
							(end 0.1778 -0.2794)
						)
					)
					(width 0)
					(fill yes)
				)
			)
		)
	)
	(footprint ""
		(layer "F.Cu")
		(at 27.178 -247.777 90)
		(property "Reference" "C598"
			(at 0 0 90)
			(layer "F.SilkS")
			(hide yes)
			(effects
				(font
					(size 1.27 1.27)
				)
			)
		)
		(property "Value" "SC10U16V5KX-7-GP-U"
			(at -0.0762 -6.1214 90)
			(unlocked yes)
			(layer "F.Fab")
			(hide yes)
			(effects
				(font
					(size 1.016 1.016)
					(thickness 0.1524)
				)
			)
		)
		(property "Device Type" "C805H58"
			(at -0.0762 -8.1534 90)
			(unlocked yes)
			(layer "F.Fab")
			(hide yes)
			(effects
				(font
					(size 1.016 1.016)
					(thickness 0.1524)
				)
			)
		)
		(duplicate_pad_numbers_are_jumpers no)
		(fp_line
			(start 0.635 0)
			(end -0.635 0)
			(stroke
				(width 0.508)
				(type default)
			)
			(layer "F.SilkS")
		)
		(fp_rect
			(start -0.9652 1.778)
			(end 0.9652 -1.778)
			(stroke
				(width 0)
				(type default)
			)
			(fill no)
			(layer "F.CrtYd")
		)
		(fp_poly
			(pts
				(xy -0.9652 -1.778) (xy 0.9652 -1.778) (xy 0.9652 1.778) (xy -0.9652 1.778)
			)
			(stroke
				(width 0)
				(type default)
			)
			(fill no)
			(layer "F.Fab")
		)
		(pad "1" smd rect
			(at 0 -0.9652 90)
			(size 1.397 1.143)
			(layers "F.Cu" "F.Mask" "F.Paste")
			(net "P12V_A_VIN_U20")
		)
		(pad "2" smd rect
			(at 0 0.9652 90)
			(size 1.397 1.143)
			(layers "F.Cu" "F.Mask" "F.Paste")
			(net "GND")
		)
	)
	(footprint ""
		(layer "F.Cu")
		(at 472.244928 -127.254)
		(property "Reference" "R343"
			(at 0 0 0)
			(layer "F.SilkS")
			(hide yes)
			(effects
				(font
					(size 1.27 1.27)
				)
			)
		)
		(property "Value" "130R3F-GP"
			(at -0.0254 -2.5146 0)
			(unlocked yes)
			(layer "F.Fab")
			(hide yes)
			(effects
				(font
					(size 1.016 1.016)
					(thickness 0.1524)
				)
			)
		)
		(property "Device Type" "R603H22"
			(at -0.0254 -4.0386 0)
			(unlocked yes)
			(layer "F.Fab")
			(hide yes)
			(effects
				(font
					(size 1.016 1.016)
					(thickness 0.1524)
				)
			)
		)
		(duplicate_pad_numbers_are_jumpers no)
		(fp_line
			(start -0.4826 0)
			(end -0.2032 0)
			(stroke
				(width 0.2032)
				(type default)
			)
			(layer "F.SilkS")
		)
		(fp_line
			(start 0.2032 0)
			(end 0.4826 0)
			(stroke
				(width 0.2032)
				(type default)
			)
			(layer "F.SilkS")
		)
		(fp_rect
			(start -0.5842 1.3335)
			(end 0.5842 -1.3335)
			(stroke
				(width 0)
				(type default)
			)
			(fill no)
			(layer "F.CrtYd")
		)
		(fp_rect
			(start -0.5842 1.3335)
			(end 0.5842 -1.3335)
			(stroke
				(width 0)
				(type default)
			)
			(fill no)
			(layer "F.Fab")
		)
		(pad "1" smd custom
			(at 0 -0.762)
			(size 0.2159 0.2159)
			(layers "F.Cu" "F.Mask" "F.Paste")
			(net "P5V_A_4")
			(options
				(clearance outline)
				(anchor circle)
			)
			(primitives
				(gr_poly
					(pts
						(arc
							(start -0.3302 -0.4318)
							(mid -0.402042 -0.402042)
							(end -0.4318 -0.3302)
						)
						(arc
							(start -0.4318 0.3302)
							(mid -0.402042 0.402042)
							(end -0.3302 0.4318)
						)
						(arc
							(start 0.3302 0.4318)
							(mid 0.402042 0.402042)
							(end 0.4318 0.3302)
						)
						(arc
							(start 0.4318 -0.3302)
							(mid 0.402042 -0.402042)
							(end 0.3302 -0.4318)
						)
					)
					(width 0)
					(fill yes)
				)
			)
		)
		(pad "2" smd custom
			(at 0 0.762)
			(size 0.2159 0.2159)
			(layers "F.Cu" "F.Mask" "F.Paste")
			(net "FLT_HDD23")
			(options
				(clearance outline)
				(anchor circle)
			)
			(primitives
				(gr_poly
					(pts
						(arc
							(start -0.3302 -0.4318)
							(mid -0.402042 -0.402042)
							(end -0.4318 -0.3302)
						)
						(arc
							(start -0.4318 0.3302)
							(mid -0.402042 0.402042)
							(end -0.3302 0.4318)
						)
						(arc
							(start 0.3302 0.4318)
							(mid 0.402042 0.402042)
							(end 0.4318 0.3302)
						)
						(arc
							(start 0.4318 -0.3302)
							(mid 0.402042 -0.402042)
							(end 0.3302 -0.4318)
						)
					)
					(width 0)
					(fill yes)
				)
			)
		)
	)
	(footprint ""
		(layer "F.Cu")
		(at 222.6056 -114.3508 -90)
		(property "Reference" "R178"
			(at 0 0 270)
			(layer "F.SilkS")
			(hide yes)
			(effects
				(font
					(size 1.27 1.27)
				)
			)
		)
		(property "Value" "0R2J-2-GP"
			(at 0.064008 -3.993896 270)
			(unlocked yes)
			(layer "F.Fab")
			(hide yes)
			(effects
				(font
					(size 1.016 1.016)
					(thickness 0.1524)
				)
			)
		)
		(property "Device Type" "R402H16"
			(at 0.064008 -5.517896 270)
			(unlocked yes)
			(layer "F.Fab")
			(hide yes)
			(effects
				(font
					(size 1.016 1.016)
					(thickness 0.1524)
				)
			)
		)
		(duplicate_pad_numbers_are_jumpers no)
		(fp_line
			(start -0.508 -0.9398)
			(end -0.508 0.9398)
			(stroke
				(width 0.1524)
				(type default)
			)
			(layer "F.SilkS")
		)
		(fp_line
			(start 0.508 -0.9398)
			(end -0.508 -0.9398)
			(stroke
				(width 0.1524)
				(type default)
			)
			(layer "F.SilkS")
		)
		(fp_rect
			(start -0.508 0.9398)
			(end 0.508 -0.9398)
			(stroke
				(width 0)
				(type default)
			)
			(fill no)
			(layer "F.CrtYd")
		)
		(fp_rect
			(start -0.508 0.9398)
			(end 0.508 -0.9398)
			(stroke
				(width 0)
				(type default)
			)
			(fill no)
			(layer "F.Fab")
		)
		(pad "1" smd custom
			(at 0 -0.4445 270)
			(size 0.1397 0.1397)
			(layers "F.Cu" "F.Mask" "F.Paste")
			(net "SLOT3_SVR_ID0_GPIO1")
			(options
				(clearance outline)
				(anchor circle)
			)
			(primitives
				(gr_poly
					(pts
						(arc
							(start -0.1778 -0.2794)
							(mid -0.249642 -0.249642)
							(end -0.2794 -0.1778)
						)
						(arc
							(start -0.2794 0.1778)
							(mid -0.249642 0.249642)
							(end -0.1778 0.2794)
						)
						(arc
							(start 0.1778 0.2794)
							(mid 0.249642 0.249642)
							(end 0.2794 0.1778)
						)
						(arc
							(start 0.2794 -0.1778)
							(mid 0.249642 -0.249642)
							(end 0.1778 -0.2794)
						)
					)
					(width 0)
					(fill yes)
				)
			)
		)
		(pad "2" smd custom
			(at 0 0.4445 270)
			(size 0.1397 0.1397)
			(layers "F.Cu" "F.Mask" "F.Paste")
			(net "COMP_A_BMC_A_SPARE_1")
			(options
				(clearance outline)
				(anchor circle)
			)
			(primitives
				(gr_poly
					(pts
						(arc
							(start -0.1778 -0.2794)
							(mid -0.249642 -0.249642)
							(end -0.2794 -0.1778)
						)
						(arc
							(start -0.2794 0.1778)
							(mid -0.249642 0.249642)
							(end -0.1778 0.2794)
						)
						(arc
							(start 0.1778 0.2794)
							(mid 0.249642 0.249642)
							(end 0.2794 0.1778)
						)
						(arc
							(start 0.2794 -0.1778)
							(mid 0.249642 -0.249642)
							(end 0.1778 -0.2794)
						)
					)
					(width 0)
					(fill yes)
				)
			)
		)
	)
)
